(kicad_pcb
	(version 20260206)
	(generator "pcbnew")
	(generator_version "10.0")
	(general
		(thickness 1.6)
		(legacy_teardrops no)
	)
	(paper "A4")
	(title_block
		(title "01162023_DA0F0TEBIF0_F0T_Expander_BD_F_brd_V02_OCP.brd")
		(comment 1 "Grand Teton / footprint 4451 of 9728 (PEX3), pads 1308-1423 of 2397")
	)
	(layers
		(0 "F.Cu" signal "TOP")
		(4 "In1.Cu" signal "GND")
		(6 "In2.Cu" signal "VCC")
		(8 "In3.Cu" signal "VCC1")
		(10 "In4.Cu" signal "GND1")
		(12 "In5.Cu" signal "IN1")
		(14 "In6.Cu" signal "GND2")
		(16 "In7.Cu" signal "IN2")
		(18 "In8.Cu" signal "GND3")
		(20 "In9.Cu" signal "IN3")
		(22 "In10.Cu" signal "GND4")
		(24 "In11.Cu" signal "IN4")
		(26 "In12.Cu" signal "GND5")
		(28 "In13.Cu" signal "IN5")
		(30 "In14.Cu" signal "GND6")
		(32 "In15.Cu" signal "IN6")
		(34 "In16.Cu" signal "GND7")
		(2 "B.Cu" signal "BOTTOM")
		(9 "F.Adhes" user "F.Adhesive")
		(11 "B.Adhes" user "B.Adhesive")
		(13 "F.Paste" user "Package Geometry/Pastemask Top")
		(15 "B.Paste" user "Package Geometry/Pastemask Bottom")
		(5 "F.SilkS" user "Ref Des/Silkscreen Top")
		(7 "B.SilkS" user "Ref Des/Silkscreen Bottom")
		(1 "F.Mask" user "Board Geometry/Soldermask Top")
		(3 "B.Mask" user "Board Geometry/Soldermask Bottom")
		(17 "Dwgs.User" user "User.Drawings")
		(19 "Cmts.User" user "User.Comments")
		(21 "Eco1.User" user "User.Eco1")
		(23 "Eco2.User" user "User.Eco2")
		(25 "Edge.Cuts" user "Board Geometry/Outline")
		(27 "Margin" user)
		(31 "F.CrtYd" user "Package Geometry/Place Bound Top")
		(29 "B.CrtYd" user "Package Geometry/Place Bound Bottom")
		(35 "F.Fab" user "Ref Des/Assembly Top")
		(33 "B.Fab" user "Ref Des/Assembly Bottom")
	)
	(footprint ""
		(layer "F.Cu")
		(at 407.949908 -295.89984)
		(property "Reference" "PEX3"
			(at -3.358642 35.5727 0)
			(unlocked yes)
			(layer "F.SilkS")
			(effects
				(font
					(size 2.032 1.524)
					(thickness 0.1524)
				)
				(justify left)
			)
		)
		(property "Value" ""
			(at 0 0 0)
			(layer "F.Fab")
			(effects
				(font
					(size 1.27 1.27)
				)
			)
		)
		(duplicate_pad_numbers_are_jumpers no)
		(pad "BE36" smd circle
			(at 10.450068 18.999962)
			(size 0.4572 0.4572)
			(layers "F.Cu" "F.Mask" "F.Paste")
			(net "GND")
		)
		(pad "BE37" smd circle
			(at 11.400028 18.999962)
			(size 0.4572 0.4572)
			(layers "F.Cu" "F.Mask" "F.Paste")
			(net "GND")
		)
		(pad "BE38" smd circle
			(at 12.349988 18.999962)
			(size 0.4572 0.4572)
			(layers "F.Cu" "F.Mask" "F.Paste")
			(net "GND")
		)
		(pad "BE39" smd circle
			(at 13.299948 18.999962)
			(size 0.4572 0.4572)
			(layers "F.Cu" "F.Mask" "F.Paste")
			(net "GND")
		)
		(pad "BE40" smd circle
			(at 14.249908 18.999962)
			(size 0.4572 0.4572)
			(layers "F.Cu" "F.Mask" "F.Paste")
			(net "GND")
		)
		(pad "BE41" smd circle
			(at 15.200122 18.999962)
			(size 0.4572 0.4572)
			(layers "F.Cu" "F.Mask" "F.Paste")
			(net "GND")
		)
		(pad "BE42" smd circle
			(at 16.150082 18.999962)
			(size 0.4572 0.4572)
			(layers "F.Cu" "F.Mask" "F.Paste")
			(net "GND")
		)
		(pad "BE43" smd circle
			(at 17.100042 18.999962)
			(size 0.4572 0.4572)
			(layers "F.Cu" "F.Mask" "F.Paste")
			(net "GND")
		)
		(pad "BE44" smd circle
			(at 18.050002 18.999962)
			(size 0.4572 0.4572)
			(layers "F.Cu" "F.Mask" "F.Paste")
			(net "GND")
		)
		(pad "BE45" smd circle
			(at 18.999962 18.999962)
			(size 0.4572 0.4572)
			(layers "F.Cu" "F.Mask" "F.Paste")
			(net "GND")
		)
		(pad "BE46" smd circle
			(at 19.949922 18.999962)
			(size 0.4572 0.4572)
			(layers "F.Cu" "F.Mask" "F.Paste")
			(net "GND")
		)
		(pad "BE47" smd circle
			(at 20.899882 18.999962)
			(size 0.4572 0.4572)
			(layers "F.Cu" "F.Mask" "F.Paste")
			(net "GND")
		)
		(pad "BE48" smd circle
			(at 21.850096 18.999962)
			(size 0.4572 0.4572)
			(layers "F.Cu" "F.Mask" "F.Paste")
			(net "P5E_PEX3_STN0_TX_DP<8>")
		)
		(pad "BE49" smd circle
			(at 22.800056 18.999962)
			(size 0.4572 0.4572)
			(layers "F.Cu" "F.Mask" "F.Paste")
			(net "P5E_PEX3_STN0_TX_DN<8>")
		)
		(pad "BF1" smd circle
			(at -22.800056 19.949922)
			(size 0.4572 0.4572)
			(layers "F.Cu" "F.Mask" "F.Paste")
			(net "GND")
		)
		(pad "BF2" smd circle
			(at -21.850096 19.949922)
			(size 0.4572 0.4572)
			(layers "F.Cu" "F.Mask" "F.Paste")
			(net "GND")
		)
		(pad "BF3" smd circle
			(at -20.899882 19.949922)
			(size 0.4572 0.4572)
			(layers "F.Cu" "F.Mask" "F.Paste")
			(net "GND")
		)
		(pad "BF4" smd circle
			(at -19.949922 19.949922)
			(size 0.4572 0.4572)
			(layers "F.Cu" "F.Mask" "F.Paste")
			(net "Net_1498")
		)
		(pad "BF5" smd circle
			(at -18.999962 19.949922)
			(size 0.4572 0.4572)
			(layers "F.Cu" "F.Mask" "F.Paste")
			(net "GND")
		)
		(pad "BF6" smd circle
			(at -18.050002 19.949922)
			(size 0.4572 0.4572)
			(layers "F.Cu" "F.Mask" "F.Paste")
			(net "Net_1489")
		)
		(pad "BF7" smd circle
			(at -17.100042 19.949922)
			(size 0.4572 0.4572)
			(layers "F.Cu" "F.Mask" "F.Paste")
			(net "GND")
		)
		(pad "BF8" smd circle
			(at -16.150082 19.949922)
			(size 0.4572 0.4572)
			(layers "F.Cu" "F.Mask" "F.Paste")
			(net "Net_1424")
		)
		(pad "BF9" smd circle
			(at -15.200122 19.949922)
			(size 0.4572 0.4572)
			(layers "F.Cu" "F.Mask" "F.Paste")
			(net "GND")
		)
		(pad "BF10" smd circle
			(at -14.249908 19.949922)
			(size 0.4572 0.4572)
			(layers "F.Cu" "F.Mask" "F.Paste")
			(net "P5E_PEX3_STN2_RX_DP<46>")
		)
		(pad "BF11" smd circle
			(at -13.299948 19.949922)
			(size 0.4572 0.4572)
			(layers "F.Cu" "F.Mask" "F.Paste")
			(net "GND")
		)
		(pad "BF12" smd circle
			(at -12.349988 19.949922)
			(size 0.4572 0.4572)
			(layers "F.Cu" "F.Mask" "F.Paste")
			(net "P5E_PEX3_STN2_RX_DP<44>")
		)
		(pad "BF13" smd circle
			(at -11.400028 19.949922)
			(size 0.4572 0.4572)
			(layers "F.Cu" "F.Mask" "F.Paste")
			(net "GND")
		)
		(pad "BF14" smd circle
			(at -10.450068 19.949922)
			(size 0.4572 0.4572)
			(layers "F.Cu" "F.Mask" "F.Paste")
			(net "P5E_PEX3_STN2_RX_DP<42>")
		)
		(pad "BF15" smd circle
			(at -9.500108 19.949922)
			(size 0.4572 0.4572)
			(layers "F.Cu" "F.Mask" "F.Paste")
			(net "GND")
		)
		(pad "BF16" smd circle
			(at -8.549894 19.949922)
			(size 0.4572 0.4572)
			(layers "F.Cu" "F.Mask" "F.Paste")
			(net "P5E_PEX3_STN2_RX_DP<40>")
		)
		(pad "BF17" smd circle
			(at -7.599934 19.949922)
			(size 0.4572 0.4572)
			(layers "F.Cu" "F.Mask" "F.Paste")
			(net "GND")
		)
		(pad "BF18" smd circle
			(at -6.649974 19.949922)
			(size 0.4572 0.4572)
			(layers "F.Cu" "F.Mask" "F.Paste")
			(net "P5E_PEX3_STN2_RX_DP<38>")
		)
		(pad "BF19" smd circle
			(at -5.700014 19.949922)
			(size 0.4572 0.4572)
			(layers "F.Cu" "F.Mask" "F.Paste")
			(net "GND")
		)
		(pad "BF20" smd circle
			(at -4.750054 19.949922)
			(size 0.4572 0.4572)
			(layers "F.Cu" "F.Mask" "F.Paste")
			(net "P5E_PEX3_STN2_RX_DP<36>")
		)
		(pad "BF21" smd circle
			(at -3.800094 19.949922)
			(size 0.4572 0.4572)
			(layers "F.Cu" "F.Mask" "F.Paste")
			(net "GND")
		)
		(pad "BF22" smd circle
			(at -2.84988 19.949922)
			(size 0.4572 0.4572)
			(layers "F.Cu" "F.Mask" "F.Paste")
			(net "P5E_PEX3_STN2_RX_DP<34>")
		)
		(pad "BF23" smd circle
			(at -1.89992 19.949922)
			(size 0.4572 0.4572)
			(layers "F.Cu" "F.Mask" "F.Paste")
			(net "GND")
		)
		(pad "BF24" smd circle
			(at -0.94996 19.949922)
			(size 0.4572 0.4572)
			(layers "F.Cu" "F.Mask" "F.Paste")
			(net "P5E_PEX3_STN2_RX_DP<32>")
		)
		(pad "BF25" smd circle
			(at 0 19.949922)
			(size 0.4572 0.4572)
			(layers "F.Cu" "F.Mask" "F.Paste")
			(net "GND")
		)
		(pad "BF26" smd circle
			(at 0.94996 19.949922)
			(size 0.4572 0.4572)
			(layers "F.Cu" "F.Mask" "F.Paste")
			(net "P5E_PEX3_STN1_RX_DP<17>")
		)
		(pad "BF27" smd circle
			(at 1.89992 19.949922)
			(size 0.4572 0.4572)
			(layers "F.Cu" "F.Mask" "F.Paste")
			(net "GND")
		)
		(pad "BF28" smd circle
			(at 2.84988 19.949922)
			(size 0.4572 0.4572)
			(layers "F.Cu" "F.Mask" "F.Paste")
			(net "P5E_PEX3_STN1_RX_DP<19>")
		)
		(pad "BF29" smd circle
			(at 3.800094 19.949922)
			(size 0.4572 0.4572)
			(layers "F.Cu" "F.Mask" "F.Paste")
			(net "GND")
		)
		(pad "BF30" smd circle
			(at 4.750054 19.949922)
			(size 0.4572 0.4572)
			(layers "F.Cu" "F.Mask" "F.Paste")
			(net "P5E_PEX3_STN1_RX_DP<21>")
		)
		(pad "BF31" smd circle
			(at 5.700014 19.949922)
			(size 0.4572 0.4572)
			(layers "F.Cu" "F.Mask" "F.Paste")
			(net "GND")
		)
		(pad "BF32" smd circle
			(at 6.649974 19.949922)
			(size 0.4572 0.4572)
			(layers "F.Cu" "F.Mask" "F.Paste")
			(net "P5E_PEX3_STN1_RX_DP<23>")
		)
		(pad "BF33" smd circle
			(at 7.599934 19.949922)
			(size 0.4572 0.4572)
			(layers "F.Cu" "F.Mask" "F.Paste")
			(net "GND")
		)
		(pad "BF34" smd circle
			(at 8.549894 19.949922)
			(size 0.4572 0.4572)
			(layers "F.Cu" "F.Mask" "F.Paste")
			(net "P5E_PEX3_STN1_RX_DP<25>")
		)
		(pad "BF35" smd circle
			(at 9.500108 19.949922)
			(size 0.4572 0.4572)
			(layers "F.Cu" "F.Mask" "F.Paste")
			(net "GND")
		)
		(pad "BF36" smd circle
			(at 10.450068 19.949922)
			(size 0.4572 0.4572)
			(layers "F.Cu" "F.Mask" "F.Paste")
			(net "P5E_PEX3_STN1_RX_DP<27>")
		)
		(pad "BF37" smd circle
			(at 11.400028 19.949922)
			(size 0.4572 0.4572)
			(layers "F.Cu" "F.Mask" "F.Paste")
			(net "GND")
		)
		(pad "BF38" smd circle
			(at 12.349988 19.949922)
			(size 0.4572 0.4572)
			(layers "F.Cu" "F.Mask" "F.Paste")
			(net "P5E_PEX3_STN1_RX_DP<29>")
		)
		(pad "BF39" smd circle
			(at 13.299948 19.949922)
			(size 0.4572 0.4572)
			(layers "F.Cu" "F.Mask" "F.Paste")
			(net "GND")
		)
		(pad "BF40" smd circle
			(at 14.249908 19.949922)
			(size 0.4572 0.4572)
			(layers "F.Cu" "F.Mask" "F.Paste")
			(net "P5E_PEX3_STN1_RX_DP<31>")
		)
		(pad "BF41" smd circle
			(at 15.200122 19.949922)
			(size 0.4572 0.4572)
			(layers "F.Cu" "F.Mask" "F.Paste")
			(net "GND")
		)
		(pad "BF42" smd circle
			(at 16.150082 19.949922)
			(size 0.4572 0.4572)
			(layers "F.Cu" "F.Mask" "F.Paste")
			(net "P5E_PEX3_STN0_RX_DP<14>")
		)
		(pad "BF43" smd circle
			(at 17.100042 19.949922)
			(size 0.4572 0.4572)
			(layers "F.Cu" "F.Mask" "F.Paste")
			(net "GND")
		)
		(pad "BF44" smd circle
			(at 18.050002 19.949922)
			(size 0.4572 0.4572)
			(layers "F.Cu" "F.Mask" "F.Paste")
			(net "P5E_PEX3_STN0_RX_DP<12>")
		)
		(pad "BF45" smd circle
			(at 18.999962 19.949922)
			(size 0.4572 0.4572)
			(layers "F.Cu" "F.Mask" "F.Paste")
			(net "GND")
		)
		(pad "BF46" smd circle
			(at 19.949922 19.949922)
			(size 0.4572 0.4572)
			(layers "F.Cu" "F.Mask" "F.Paste")
			(net "P5E_PEX3_STN0_RX_DP<10>")
		)
		(pad "BF47" smd circle
			(at 20.899882 19.949922)
			(size 0.4572 0.4572)
			(layers "F.Cu" "F.Mask" "F.Paste")
			(net "GND")
		)
		(pad "BF48" smd circle
			(at 21.850096 19.949922)
			(size 0.4572 0.4572)
			(layers "F.Cu" "F.Mask" "F.Paste")
			(net "GND")
		)
		(pad "BF49" smd circle
			(at 22.800056 19.949922)
			(size 0.4572 0.4572)
			(layers "F.Cu" "F.Mask" "F.Paste")
			(net "GND")
		)
		(pad "BG1" smd circle
			(at -22.800056 20.899882)
			(size 0.4572 0.4572)
			(layers "F.Cu" "F.Mask" "F.Paste")
			(net "Net_1462")
		)
		(pad "BG2" smd circle
			(at -21.850096 20.899882)
			(size 0.4572 0.4572)
			(layers "F.Cu" "F.Mask" "F.Paste")
			(net "Net_1500")
		)
		(pad "BG3" smd circle
			(at -20.899882 20.899882)
			(size 0.4572 0.4572)
			(layers "F.Cu" "F.Mask" "F.Paste")
			(net "GND")
		)
		(pad "BG4" smd circle
			(at -19.949922 20.899882)
			(size 0.4572 0.4572)
			(layers "F.Cu" "F.Mask" "F.Paste")
			(net "Net_1404")
		)
		(pad "BG5" smd circle
			(at -18.999962 20.899882)
			(size 0.4572 0.4572)
			(layers "F.Cu" "F.Mask" "F.Paste")
			(net "GND")
		)
		(pad "BG6" smd circle
			(at -18.050002 20.899882)
			(size 0.4572 0.4572)
			(layers "F.Cu" "F.Mask" "F.Paste")
			(net "Net_1492")
		)
		(pad "BG7" smd circle
			(at -17.100042 20.899882)
			(size 0.4572 0.4572)
			(layers "F.Cu" "F.Mask" "F.Paste")
			(net "GND")
		)
		(pad "BG8" smd circle
			(at -16.150082 20.899882)
			(size 0.4572 0.4572)
			(layers "F.Cu" "F.Mask" "F.Paste")
			(net "Net_1477")
		)
		(pad "BG9" smd circle
			(at -15.200122 20.899882)
			(size 0.4572 0.4572)
			(layers "F.Cu" "F.Mask" "F.Paste")
			(net "GND")
		)
		(pad "BG10" smd circle
			(at -14.249908 20.899882)
			(size 0.4572 0.4572)
			(layers "F.Cu" "F.Mask" "F.Paste")
			(net "P5E_PEX3_STN2_RX_DN<46>")
		)
		(pad "BG11" smd circle
			(at -13.299948 20.899882)
			(size 0.4572 0.4572)
			(layers "F.Cu" "F.Mask" "F.Paste")
			(net "GND")
		)
		(pad "BG12" smd circle
			(at -12.349988 20.899882)
			(size 0.4572 0.4572)
			(layers "F.Cu" "F.Mask" "F.Paste")
			(net "P5E_PEX3_STN2_RX_DN<44>")
		)
		(pad "BG13" smd circle
			(at -11.400028 20.899882)
			(size 0.4572 0.4572)
			(layers "F.Cu" "F.Mask" "F.Paste")
			(net "GND")
		)
		(pad "BG14" smd circle
			(at -10.450068 20.899882)
			(size 0.4572 0.4572)
			(layers "F.Cu" "F.Mask" "F.Paste")
			(net "P5E_PEX3_STN2_RX_DN<42>")
		)
		(pad "BG15" smd circle
			(at -9.500108 20.899882)
			(size 0.4572 0.4572)
			(layers "F.Cu" "F.Mask" "F.Paste")
			(net "GND")
		)
		(pad "BG16" smd circle
			(at -8.549894 20.899882)
			(size 0.4572 0.4572)
			(layers "F.Cu" "F.Mask" "F.Paste")
			(net "P5E_PEX3_STN2_RX_DN<40>")
		)
		(pad "BG17" smd circle
			(at -7.599934 20.899882)
			(size 0.4572 0.4572)
			(layers "F.Cu" "F.Mask" "F.Paste")
			(net "GND")
		)
		(pad "BG18" smd circle
			(at -6.649974 20.899882)
			(size 0.4572 0.4572)
			(layers "F.Cu" "F.Mask" "F.Paste")
			(net "P5E_PEX3_STN2_RX_DN<38>")
		)
		(pad "BG19" smd circle
			(at -5.700014 20.899882)
			(size 0.4572 0.4572)
			(layers "F.Cu" "F.Mask" "F.Paste")
			(net "GND")
		)
		(pad "BG20" smd circle
			(at -4.750054 20.899882)
			(size 0.4572 0.4572)
			(layers "F.Cu" "F.Mask" "F.Paste")
			(net "P5E_PEX3_STN2_RX_DN<36>")
		)
		(pad "BG21" smd circle
			(at -3.800094 20.899882)
			(size 0.4572 0.4572)
			(layers "F.Cu" "F.Mask" "F.Paste")
			(net "GND")
		)
		(pad "BG22" smd circle
			(at -2.84988 20.899882)
			(size 0.4572 0.4572)
			(layers "F.Cu" "F.Mask" "F.Paste")
			(net "P5E_PEX3_STN2_RX_DN<34>")
		)
		(pad "BG23" smd circle
			(at -1.89992 20.899882)
			(size 0.4572 0.4572)
			(layers "F.Cu" "F.Mask" "F.Paste")
			(net "GND")
		)
		(pad "BG24" smd circle
			(at -0.94996 20.899882)
			(size 0.4572 0.4572)
			(layers "F.Cu" "F.Mask" "F.Paste")
			(net "P5E_PEX3_STN2_RX_DN<32>")
		)
		(pad "BG25" smd circle
			(at 0 20.899882)
			(size 0.4572 0.4572)
			(layers "F.Cu" "F.Mask" "F.Paste")
			(net "GND")
		)
		(pad "BG26" smd circle
			(at 0.94996 20.899882)
			(size 0.4572 0.4572)
			(layers "F.Cu" "F.Mask" "F.Paste")
			(net "P5E_PEX3_STN1_RX_DN<17>")
		)
		(pad "BG27" smd circle
			(at 1.89992 20.899882)
			(size 0.4572 0.4572)
			(layers "F.Cu" "F.Mask" "F.Paste")
			(net "GND")
		)
		(pad "BG28" smd circle
			(at 2.84988 20.899882)
			(size 0.4572 0.4572)
			(layers "F.Cu" "F.Mask" "F.Paste")
			(net "P5E_PEX3_STN1_RX_DN<19>")
		)
		(pad "BG29" smd circle
			(at 3.800094 20.899882)
			(size 0.4572 0.4572)
			(layers "F.Cu" "F.Mask" "F.Paste")
			(net "GND")
		)
		(pad "BG30" smd circle
			(at 4.750054 20.899882)
			(size 0.4572 0.4572)
			(layers "F.Cu" "F.Mask" "F.Paste")
			(net "P5E_PEX3_STN1_RX_DN<21>")
		)
		(pad "BG31" smd circle
			(at 5.700014 20.899882)
			(size 0.4572 0.4572)
			(layers "F.Cu" "F.Mask" "F.Paste")
			(net "GND")
		)
		(pad "BG32" smd circle
			(at 6.649974 20.899882)
			(size 0.4572 0.4572)
			(layers "F.Cu" "F.Mask" "F.Paste")
			(net "P5E_PEX3_STN1_RX_DN<23>")
		)
		(pad "BG33" smd circle
			(at 7.599934 20.899882)
			(size 0.4572 0.4572)
			(layers "F.Cu" "F.Mask" "F.Paste")
			(net "GND")
		)
		(pad "BG34" smd circle
			(at 8.549894 20.899882)
			(size 0.4572 0.4572)
			(layers "F.Cu" "F.Mask" "F.Paste")
			(net "P5E_PEX3_STN1_RX_DN<25>")
		)
		(pad "BG35" smd circle
			(at 9.500108 20.899882)
			(size 0.4572 0.4572)
			(layers "F.Cu" "F.Mask" "F.Paste")
			(net "GND")
		)
		(pad "BG36" smd circle
			(at 10.450068 20.899882)
			(size 0.4572 0.4572)
			(layers "F.Cu" "F.Mask" "F.Paste")
			(net "P5E_PEX3_STN1_RX_DN<27>")
		)
		(pad "BG37" smd circle
			(at 11.400028 20.899882)
			(size 0.4572 0.4572)
			(layers "F.Cu" "F.Mask" "F.Paste")
			(net "GND")
		)
		(pad "BG38" smd circle
			(at 12.349988 20.899882)
			(size 0.4572 0.4572)
			(layers "F.Cu" "F.Mask" "F.Paste")
			(net "P5E_PEX3_STN1_RX_DN<29>")
		)
		(pad "BG39" smd circle
			(at 13.299948 20.899882)
			(size 0.4572 0.4572)
			(layers "F.Cu" "F.Mask" "F.Paste")
			(net "GND")
		)
		(pad "BG40" smd circle
			(at 14.249908 20.899882)
			(size 0.4572 0.4572)
			(layers "F.Cu" "F.Mask" "F.Paste")
			(net "P5E_PEX3_STN1_RX_DN<31>")
		)
		(pad "BG41" smd circle
			(at 15.200122 20.899882)
			(size 0.4572 0.4572)
			(layers "F.Cu" "F.Mask" "F.Paste")
			(net "GND")
		)
		(pad "BG42" smd circle
			(at 16.150082 20.899882)
			(size 0.4572 0.4572)
			(layers "F.Cu" "F.Mask" "F.Paste")
			(net "P5E_PEX3_STN0_RX_DN<14>")
		)
		(pad "BG43" smd circle
			(at 17.100042 20.899882)
			(size 0.4572 0.4572)
			(layers "F.Cu" "F.Mask" "F.Paste")
			(net "GND")
		)
		(pad "BG44" smd circle
			(at 18.050002 20.899882)
			(size 0.4572 0.4572)
			(layers "F.Cu" "F.Mask" "F.Paste")
			(net "P5E_PEX3_STN0_RX_DN<12>")
		)
		(pad "BG45" smd circle
			(at 18.999962 20.899882)
			(size 0.4572 0.4572)
			(layers "F.Cu" "F.Mask" "F.Paste")
			(net "GND")
		)
		(pad "BG46" smd circle
			(at 19.949922 20.899882)
			(size 0.4572 0.4572)
			(layers "F.Cu" "F.Mask" "F.Paste")
			(net "P5E_PEX3_STN0_RX_DN<10>")
		)
		(pad "BG47" smd circle
			(at 20.899882 20.899882)
			(size 0.4572 0.4572)
			(layers "F.Cu" "F.Mask" "F.Paste")
			(net "GND")
		)
		(pad "BG48" smd circle
			(at 21.850096 20.899882)
			(size 0.4572 0.4572)
			(layers "F.Cu" "F.Mask" "F.Paste")
			(net "P5E_PEX3_STN0_RX_DP<8>")
		)
		(pad "BG49" smd circle
			(at 22.800056 20.899882)
			(size 0.4572 0.4572)
			(layers "F.Cu" "F.Mask" "F.Paste")
			(net "P5E_PEX3_STN0_RX_DN<8>")
		)
		(pad "BH1" smd circle
			(at -22.800056 21.850096)
			(size 0.4572 0.4572)
			(layers "F.Cu" "F.Mask" "F.Paste")
			(net "GND")
		)
		(pad "BH2" smd circle
			(at -21.850096 21.850096)
			(size 0.4572 0.4572)
			(layers "F.Cu" "F.Mask" "F.Paste")
			(net "GND")
		)
		(pad "BH3" smd circle
			(at -20.899882 21.850096)
			(size 0.4572 0.4572)
			(layers "F.Cu" "F.Mask" "F.Paste")
			(net "Net_1479")
		)
		(pad "BH4" smd circle
			(at -19.949922 21.850096)
			(size 0.4572 0.4572)
			(layers "F.Cu" "F.Mask" "F.Paste")
			(net "GND")
		)
	)
)
